(kicad_pcb
	(version 20260206)
	(generator "pcbnew")
	(generator_version "10.0")
	(general
		(thickness 1.6)
		(legacy_teardrops no)
	)
	(paper "A4")
	(title_block
		(title "03242023_DA0F0TMBIJ0_F0T_Motherboard_J_brd_V01_OCP.brd")
		(comment 1 "Grand Teton / footprints 5639-5644 of 6105")
	)
	(layers
		(0 "F.Cu" signal "TOP")
		(4 "In1.Cu" signal "GND")
		(6 "In2.Cu" signal "IN1")
		(8 "In3.Cu" signal "GND1")
		(10 "In4.Cu" signal "IN2")
		(12 "In5.Cu" signal "GND2")
		(14 "In6.Cu" signal "IN3")
		(16 "In7.Cu" signal "GND3")
		(18 "In8.Cu" signal "VCC")
		(20 "In9.Cu" signal "VCC1")
		(22 "In10.Cu" signal "GND4")
		(24 "In11.Cu" signal "IN4")
		(26 "In12.Cu" signal "GND5")
		(28 "In13.Cu" signal "IN5")
		(30 "In14.Cu" signal "GND6")
		(32 "In15.Cu" signal "IN6")
		(34 "In16.Cu" signal "GND7")
		(2 "B.Cu" signal "BOTTOM")
		(9 "F.Adhes" user "F.Adhesive")
		(11 "B.Adhes" user "B.Adhesive")
		(13 "F.Paste" user "Package Geometry/Pastemask Top")
		(15 "B.Paste" user "Package Geometry/Pastemask Bottom")
		(5 "F.SilkS" user "Ref Des/Silkscreen Top")
		(7 "B.SilkS" user "Ref Des/Silkscreen Bottom")
		(1 "F.Mask" user "Board Geometry/Soldermask Top")
		(3 "B.Mask" user "Board Geometry/Soldermask Bottom")
		(17 "Dwgs.User" user "User.Drawings")
		(19 "Cmts.User" user "User.Comments")
		(21 "Eco1.User" user "User.Eco1")
		(23 "Eco2.User" user "User.Eco2")
		(25 "Edge.Cuts" user "Board Geometry/Outline")
		(27 "Margin" user)
		(31 "F.CrtYd" user "Package Geometry/Place Bound Top")
		(29 "B.CrtYd" user "Package Geometry/Place Bound Bottom")
		(35 "F.Fab" user "Ref Des/Assembly Top")
		(33 "B.Fab" user "Ref Des/Assembly Bottom")
	)
	(footprint ""
		(layer "B.Cu")
		(at 164.64788 -105.755948 180)
		(property "Reference" "R2663"
			(at 0 0 0)
			(layer "B.SilkS")
			(hide yes)
			(effects
				(font
					(size 1.27 1.27)
				)
				(justify mirror)
			)
		)
		(property "Value" ""
			(at 0 0 0)
			(layer "B.Fab")
			(effects
				(font
					(size 1.27 1.27)
				)
				(justify mirror)
			)
		)
		(duplicate_pad_numbers_are_jumpers no)
		(fp_line
			(start 0.7874 0.4064)
			(end 0.7874 -0.4064)
			(stroke
				(width 0.1524)
				(type default)
			)
			(layer "B.SilkS")
		)
		(fp_line
			(start 0.7874 -0.4064)
			(end -0.7874 -0.4064)
			(stroke
				(width 0.1524)
				(type default)
			)
			(layer "B.SilkS")
		)
		(fp_line
			(start -0.7874 0.4064)
			(end 0.7874 0.4064)
			(stroke
				(width 0.1524)
				(type default)
			)
			(layer "B.SilkS")
		)
		(fp_line
			(start -0.7874 -0.4064)
			(end -0.7874 0.4064)
			(stroke
				(width 0.1524)
				(type default)
			)
			(layer "B.SilkS")
		)
		(fp_line
			(start 0.67945 0.3048)
			(end 0.67945 -0.305054)
			(stroke
				(width 0.1)
				(type default)
			)
			(layer "B.Fab")
		)
		(fp_line
			(start 0.67945 -0.305054)
			(end 0.12065 -0.305054)
			(stroke
				(width 0.1)
				(type default)
			)
			(layer "B.Fab")
		)
		(fp_line
			(start 0.12065 0.3048)
			(end 0.67945 0.3048)
			(stroke
				(width 0.1)
				(type default)
			)
			(layer "B.Fab")
		)
		(fp_line
			(start 0.12065 0.2794)
			(end 0.12065 0.3048)
			(stroke
				(width 0.1)
				(type default)
			)
			(layer "B.Fab")
		)
		(fp_line
			(start 0.12065 -0.2794)
			(end -0.12065 -0.2794)
			(stroke
				(width 0.1)
				(type default)
			)
			(layer "B.Fab")
		)
		(fp_line
			(start 0.12065 -0.305054)
			(end 0.12065 -0.2794)
			(stroke
				(width 0.1)
				(type default)
			)
			(layer "B.Fab")
		)
		(fp_line
			(start -0.120396 0.3048)
			(end -0.120396 0.2794)
			(stroke
				(width 0.1)
				(type default)
			)
			(layer "B.Fab")
		)
		(fp_line
			(start -0.120396 0.2794)
			(end 0.12065 0.2794)
			(stroke
				(width 0.1)
				(type default)
			)
			(layer "B.Fab")
		)
		(fp_line
			(start -0.12065 -0.2794)
			(end -0.12065 -0.3048)
			(stroke
				(width 0.1)
				(type default)
			)
			(layer "B.Fab")
		)
		(fp_line
			(start -0.12065 -0.3048)
			(end -0.67945 -0.3048)
			(stroke
				(width 0.1)
				(type default)
			)
			(layer "B.Fab")
		)
		(fp_line
			(start -0.67945 0.3048)
			(end -0.120396 0.3048)
			(stroke
				(width 0.1)
				(type default)
			)
			(layer "B.Fab")
		)
		(fp_line
			(start -0.67945 -0.3048)
			(end -0.67945 0.3048)
			(stroke
				(width 0.1)
				(type default)
			)
			(layer "B.Fab")
		)
		(pad "1" smd circle
			(at 0.40005 0)
			(size 0 0)
			(layers "B.Cu" "B.Mask" "B.Paste")
			(net "FM_SWB_PWRGD_ISO")
		)
		(pad "2" smd circle
			(at -0.40005 0)
			(size 0 0)
			(layers "B.Cu" "B.Mask" "B.Paste")
			(net "FM_SWB_PWRGD_ISO_R")
		)
	)
	(footprint ""
		(layer "B.Cu")
		(at 169.521632 -354.571554 -90)
		(property "Reference" "PR226"
			(at 0 0 90)
			(layer "B.SilkS")
			(hide yes)
			(effects
				(font
					(size 1.27 1.27)
				)
				(justify mirror)
			)
		)
		(property "Value" ""
			(at 0 0 90)
			(layer "B.Fab")
			(effects
				(font
					(size 1.27 1.27)
				)
				(justify mirror)
			)
		)
		(duplicate_pad_numbers_are_jumpers no)
		(fp_line
			(start -0.7874 0.4064)
			(end 0.7874 0.4064)
			(stroke
				(width 0.1524)
				(type default)
			)
			(layer "B.SilkS")
		)
		(fp_line
			(start 0.7874 0.4064)
			(end 0.7874 -0.4064)
			(stroke
				(width 0.1524)
				(type default)
			)
			(layer "B.SilkS")
		)
		(fp_line
			(start -0.7874 -0.4064)
			(end -0.7874 0.4064)
			(stroke
				(width 0.1524)
				(type default)
			)
			(layer "B.SilkS")
		)
		(fp_line
			(start 0.7874 -0.4064)
			(end -0.7874 -0.4064)
			(stroke
				(width 0.1524)
				(type default)
			)
			(layer "B.SilkS")
		)
		(fp_line
			(start -0.67945 0.3048)
			(end -0.120396 0.3048)
			(stroke
				(width 0.1)
				(type default)
			)
			(layer "B.Fab")
		)
		(fp_line
			(start -0.120396 0.3048)
			(end -0.120396 0.2794)
			(stroke
				(width 0.1)
				(type default)
			)
			(layer "B.Fab")
		)
		(fp_line
			(start 0.12065 0.3048)
			(end 0.67945 0.3048)
			(stroke
				(width 0.1)
				(type default)
			)
			(layer "B.Fab")
		)
		(fp_line
			(start 0.67945 0.3048)
			(end 0.67945 -0.305054)
			(stroke
				(width 0.1)
				(type default)
			)
			(layer "B.Fab")
		)
		(fp_line
			(start -0.120396 0.2794)
			(end 0.12065 0.2794)
			(stroke
				(width 0.1)
				(type default)
			)
			(layer "B.Fab")
		)
		(fp_line
			(start 0.12065 0.2794)
			(end 0.12065 0.3048)
			(stroke
				(width 0.1)
				(type default)
			)
			(layer "B.Fab")
		)
		(fp_line
			(start -0.12065 -0.2794)
			(end -0.12065 -0.3048)
			(stroke
				(width 0.1)
				(type default)
			)
			(layer "B.Fab")
		)
		(fp_line
			(start 0.12065 -0.2794)
			(end -0.12065 -0.2794)
			(stroke
				(width 0.1)
				(type default)
			)
			(layer "B.Fab")
		)
		(fp_line
			(start -0.67945 -0.3048)
			(end -0.67945 0.3048)
			(stroke
				(width 0.1)
				(type default)
			)
			(layer "B.Fab")
		)
		(fp_line
			(start -0.12065 -0.3048)
			(end -0.67945 -0.3048)
			(stroke
				(width 0.1)
				(type default)
			)
			(layer "B.Fab")
		)
		(fp_line
			(start 0.12065 -0.305054)
			(end 0.12065 -0.2794)
			(stroke
				(width 0.1)
				(type default)
			)
			(layer "B.Fab")
		)
		(fp_line
			(start 0.67945 -0.305054)
			(end 0.12065 -0.305054)
			(stroke
				(width 0.1)
				(type default)
			)
			(layer "B.Fab")
		)
		(pad "1" smd circle
			(at 0.40005 0 90)
			(size 0 0)
			(layers "B.Cu" "B.Mask" "B.Paste")
			(net "PVCCFA_EHV_FIVRA_CPU1_PVCC1")
		)
		(pad "2" smd circle
			(at -0.40005 0 90)
			(size 0 0)
			(layers "B.Cu" "B.Mask" "B.Paste")
			(net "PVCCFA_EHV_FIVRA_CPU1_VDD1")
		)
	)
	(footprint ""
		(layer "B.Cu")
		(at 252.05563 -105.256584 -90)
		(property "Reference" "C1324"
			(at 0 0 90)
			(layer "B.SilkS")
			(hide yes)
			(effects
				(font
					(size 1.27 1.27)
				)
				(justify mirror)
			)
		)
		(property "Value" ""
			(at 0 0 90)
			(layer "B.Fab")
			(effects
				(font
					(size 1.27 1.27)
				)
				(justify mirror)
			)
		)
		(duplicate_pad_numbers_are_jumpers no)
		(fp_line
			(start -0.7874 0.4064)
			(end 0.7874 0.4064)
			(stroke
				(width 0.1524)
				(type default)
			)
			(layer "B.SilkS")
		)
		(fp_line
			(start 0.7874 0.4064)
			(end 0.7874 -0.4064)
			(stroke
				(width 0.1524)
				(type default)
			)
			(layer "B.SilkS")
		)
		(fp_line
			(start -0.7874 -0.4064)
			(end -0.7874 0.4064)
			(stroke
				(width 0.1524)
				(type default)
			)
			(layer "B.SilkS")
		)
		(fp_line
			(start 0.7874 -0.4064)
			(end -0.7874 -0.4064)
			(stroke
				(width 0.1524)
				(type default)
			)
			(layer "B.SilkS")
		)
		(fp_line
			(start -0.67945 0.3048)
			(end -0.120396 0.3048)
			(stroke
				(width 0.1)
				(type default)
			)
			(layer "B.Fab")
		)
		(fp_line
			(start -0.120396 0.3048)
			(end -0.120396 0.2794)
			(stroke
				(width 0.1)
				(type default)
			)
			(layer "B.Fab")
		)
		(fp_line
			(start 0.12065 0.3048)
			(end 0.67945 0.3048)
			(stroke
				(width 0.1)
				(type default)
			)
			(layer "B.Fab")
		)
		(fp_line
			(start 0.67945 0.3048)
			(end 0.67945 -0.305054)
			(stroke
				(width 0.1)
				(type default)
			)
			(layer "B.Fab")
		)
		(fp_line
			(start -0.120396 0.2794)
			(end 0.12065 0.2794)
			(stroke
				(width 0.1)
				(type default)
			)
			(layer "B.Fab")
		)
		(fp_line
			(start 0.12065 0.2794)
			(end 0.12065 0.3048)
			(stroke
				(width 0.1)
				(type default)
			)
			(layer "B.Fab")
		)
		(fp_line
			(start -0.12065 -0.2794)
			(end -0.12065 -0.3048)
			(stroke
				(width 0.1)
				(type default)
			)
			(layer "B.Fab")
		)
		(fp_line
			(start 0.12065 -0.2794)
			(end -0.12065 -0.2794)
			(stroke
				(width 0.1)
				(type default)
			)
			(layer "B.Fab")
		)
		(fp_line
			(start -0.67945 -0.3048)
			(end -0.67945 0.3048)
			(stroke
				(width 0.1)
				(type default)
			)
			(layer "B.Fab")
		)
		(fp_line
			(start -0.12065 -0.3048)
			(end -0.67945 -0.3048)
			(stroke
				(width 0.1)
				(type default)
			)
			(layer "B.Fab")
		)
		(fp_line
			(start 0.12065 -0.305054)
			(end 0.12065 -0.2794)
			(stroke
				(width 0.1)
				(type default)
			)
			(layer "B.Fab")
		)
		(fp_line
			(start 0.67945 -0.305054)
			(end 0.12065 -0.305054)
			(stroke
				(width 0.1)
				(type default)
			)
			(layer "B.Fab")
		)
		(pad "1" smd circle
			(at 0.40005 0 90)
			(size 0 0)
			(layers "B.Cu" "B.Mask" "B.Paste")
			(net "FM_CK440Q_DEV_25M_EN")
		)
		(pad "2" smd circle
			(at -0.40005 0 90)
			(size 0 0)
			(layers "B.Cu" "B.Mask" "B.Paste")
			(net "GND")
		)
	)
	(footprint ""
		(layer "B.Cu")
		(at 435.549802 -13.120116 180)
		(property "Reference" "C1237"
			(at 0 0 0)
			(layer "B.SilkS")
			(hide yes)
			(effects
				(font
					(size 1.27 1.27)
				)
				(justify mirror)
			)
		)
		(property "Value" ""
			(at 0 0 0)
			(layer "B.Fab")
			(effects
				(font
					(size 1.27 1.27)
				)
				(justify mirror)
			)
		)
		(duplicate_pad_numbers_are_jumpers no)
		(fp_line
			(start 0.7874 0.4064)
			(end 0.7874 -0.4064)
			(stroke
				(width 0.1524)
				(type default)
			)
			(layer "B.SilkS")
		)
		(fp_line
			(start 0.7874 -0.4064)
			(end -0.7874 -0.4064)
			(stroke
				(width 0.1524)
				(type default)
			)
			(layer "B.SilkS")
		)
		(fp_line
			(start -0.7874 0.4064)
			(end 0.7874 0.4064)
			(stroke
				(width 0.1524)
				(type default)
			)
			(layer "B.SilkS")
		)
		(fp_line
			(start -0.7874 -0.4064)
			(end -0.7874 0.4064)
			(stroke
				(width 0.1524)
				(type default)
			)
			(layer "B.SilkS")
		)
		(fp_line
			(start 0.67945 0.3048)
			(end 0.67945 -0.305054)
			(stroke
				(width 0.1)
				(type default)
			)
			(layer "B.Fab")
		)
		(fp_line
			(start 0.67945 -0.305054)
			(end 0.12065 -0.305054)
			(stroke
				(width 0.1)
				(type default)
			)
			(layer "B.Fab")
		)
		(fp_line
			(start 0.12065 0.3048)
			(end 0.67945 0.3048)
			(stroke
				(width 0.1)
				(type default)
			)
			(layer "B.Fab")
		)
		(fp_line
			(start 0.12065 0.2794)
			(end 0.12065 0.3048)
			(stroke
				(width 0.1)
				(type default)
			)
			(layer "B.Fab")
		)
		(fp_line
			(start 0.12065 -0.2794)
			(end -0.12065 -0.2794)
			(stroke
				(width 0.1)
				(type default)
			)
			(layer "B.Fab")
		)
		(fp_line
			(start 0.12065 -0.305054)
			(end 0.12065 -0.2794)
			(stroke
				(width 0.1)
				(type default)
			)
			(layer "B.Fab")
		)
		(fp_line
			(start -0.120396 0.3048)
			(end -0.120396 0.2794)
			(stroke
				(width 0.1)
				(type default)
			)
			(layer "B.Fab")
		)
		(fp_line
			(start -0.120396 0.2794)
			(end 0.12065 0.2794)
			(stroke
				(width 0.1)
				(type default)
			)
			(layer "B.Fab")
		)
		(fp_line
			(start -0.12065 -0.2794)
			(end -0.12065 -0.3048)
			(stroke
				(width 0.1)
				(type default)
			)
			(layer "B.Fab")
		)
		(fp_line
			(start -0.12065 -0.3048)
			(end -0.67945 -0.3048)
			(stroke
				(width 0.1)
				(type default)
			)
			(layer "B.Fab")
		)
		(fp_line
			(start -0.67945 0.3048)
			(end -0.120396 0.3048)
			(stroke
				(width 0.1)
				(type default)
			)
			(layer "B.Fab")
		)
		(fp_line
			(start -0.67945 -0.3048)
			(end -0.67945 0.3048)
			(stroke
				(width 0.1)
				(type default)
			)
			(layer "B.Fab")
		)
		(pad "1" smd circle
			(at 0.40005 0)
			(size 0 0)
			(layers "B.Cu" "B.Mask" "B.Paste")
			(net "P3V3_OCP_SFF")
		)
		(pad "2" smd circle
			(at -0.40005 0)
			(size 0 0)
			(layers "B.Cu" "B.Mask" "B.Paste")
			(net "GND")
		)
	)
	(footprint ""
		(layer "B.Cu")
		(at 166.386002 -251.267214 180)
		(property "Reference" "R1230"
			(at 0 0 0)
			(layer "B.SilkS")
			(hide yes)
			(effects
				(font
					(size 1.27 1.27)
				)
				(justify mirror)
			)
		)
		(property "Value" ""
			(at 0 0 0)
			(layer "B.Fab")
			(effects
				(font
					(size 1.27 1.27)
				)
				(justify mirror)
			)
		)
		(duplicate_pad_numbers_are_jumpers no)
		(fp_line
			(start 0.7874 0.4064)
			(end 0.7874 -0.4064)
			(stroke
				(width 0.1524)
				(type default)
			)
			(layer "B.SilkS")
		)
		(fp_line
			(start 0.7874 -0.4064)
			(end -0.7874 -0.4064)
			(stroke
				(width 0.1524)
				(type default)
			)
			(layer "B.SilkS")
		)
		(fp_line
			(start -0.7874 0.4064)
			(end 0.7874 0.4064)
			(stroke
				(width 0.1524)
				(type default)
			)
			(layer "B.SilkS")
		)
		(fp_line
			(start -0.7874 -0.4064)
			(end -0.7874 0.4064)
			(stroke
				(width 0.1524)
				(type default)
			)
			(layer "B.SilkS")
		)
		(fp_line
			(start 0.67945 0.3048)
			(end 0.67945 -0.305054)
			(stroke
				(width 0.1)
				(type default)
			)
			(layer "B.Fab")
		)
		(fp_line
			(start 0.67945 -0.305054)
			(end 0.12065 -0.305054)
			(stroke
				(width 0.1)
				(type default)
			)
			(layer "B.Fab")
		)
		(fp_line
			(start 0.12065 0.3048)
			(end 0.67945 0.3048)
			(stroke
				(width 0.1)
				(type default)
			)
			(layer "B.Fab")
		)
		(fp_line
			(start 0.12065 0.2794)
			(end 0.12065 0.3048)
			(stroke
				(width 0.1)
				(type default)
			)
			(layer "B.Fab")
		)
		(fp_line
			(start 0.12065 -0.2794)
			(end -0.12065 -0.2794)
			(stroke
				(width 0.1)
				(type default)
			)
			(layer "B.Fab")
		)
		(fp_line
			(start 0.12065 -0.305054)
			(end 0.12065 -0.2794)
			(stroke
				(width 0.1)
				(type default)
			)
			(layer "B.Fab")
		)
		(fp_line
			(start -0.120396 0.3048)
			(end -0.120396 0.2794)
			(stroke
				(width 0.1)
				(type default)
			)
			(layer "B.Fab")
		)
		(fp_line
			(start -0.120396 0.2794)
			(end 0.12065 0.2794)
			(stroke
				(width 0.1)
				(type default)
			)
			(layer "B.Fab")
		)
		(fp_line
			(start -0.12065 -0.2794)
			(end -0.12065 -0.3048)
			(stroke
				(width 0.1)
				(type default)
			)
			(layer "B.Fab")
		)
		(fp_line
			(start -0.12065 -0.3048)
			(end -0.67945 -0.3048)
			(stroke
				(width 0.1)
				(type default)
			)
			(layer "B.Fab")
		)
		(fp_line
			(start -0.67945 0.3048)
			(end -0.120396 0.3048)
			(stroke
				(width 0.1)
				(type default)
			)
			(layer "B.Fab")
		)
		(fp_line
			(start -0.67945 -0.3048)
			(end -0.67945 0.3048)
			(stroke
				(width 0.1)
				(type default)
			)
			(layer "B.Fab")
		)
		(pad "1" smd circle
			(at 0.40005 0)
			(size 0 0)
			(layers "B.Cu" "B.Mask" "B.Paste")
			(net "PVNN_TERM_CPU1")
		)
		(pad "2" smd circle
			(at -0.40005 0)
			(size 0 0)
			(layers "B.Cu" "B.Mask" "B.Paste")
			(net "PUD_XTAL_CPU1_MODE1")
		)
	)
	(footprint ""
		(layer "B.Cu")
		(at 334.341978 -190.82893 90)
		(property "Reference" "R22"
			(at 0 0 90)
			(layer "B.SilkS")
			(hide yes)
			(effects
				(font
					(size 1.27 1.27)
				)
				(justify mirror)
			)
		)
		(property "Value" ""
			(at 0 0 90)
			(layer "B.Fab")
			(effects
				(font
					(size 1.27 1.27)
				)
				(justify mirror)
			)
		)
		(duplicate_pad_numbers_are_jumpers no)
		(fp_line
			(start 0.7874 -0.4064)
			(end -0.7874 -0.4064)
			(stroke
				(width 0.1524)
				(type default)
			)
			(layer "B.SilkS")
		)
		(fp_line
			(start -0.7874 -0.4064)
			(end -0.7874 0.4064)
			(stroke
				(width 0.1524)
				(type default)
			)
			(layer "B.SilkS")
		)
		(fp_line
			(start 0.7874 0.4064)
			(end 0.7874 -0.4064)
			(stroke
				(width 0.1524)
				(type default)
			)
			(layer "B.SilkS")
		)
		(fp_line
			(start -0.7874 0.4064)
			(end 0.7874 0.4064)
			(stroke
				(width 0.1524)
				(type default)
			)
			(layer "B.SilkS")
		)
		(fp_line
			(start 0.67945 -0.305054)
			(end 0.12065 -0.305054)
			(stroke
				(width 0.1)
				(type default)
			)
			(layer "B.Fab")
		)
		(fp_line
			(start 0.12065 -0.305054)
			(end 0.12065 -0.2794)
			(stroke
				(width 0.1)
				(type default)
			)
			(layer "B.Fab")
		)
		(fp_line
			(start -0.12065 -0.3048)
			(end -0.67945 -0.3048)
			(stroke
				(width 0.1)
				(type default)
			)
			(layer "B.Fab")
		)
		(fp_line
			(start -0.67945 -0.3048)
			(end -0.67945 0.3048)
			(stroke
				(width 0.1)
				(type default)
			)
			(layer "B.Fab")
		)
		(fp_line
			(start 0.12065 -0.2794)
			(end -0.12065 -0.2794)
			(stroke
				(width 0.1)
				(type default)
			)
			(layer "B.Fab")
		)
		(fp_line
			(start -0.12065 -0.2794)
			(end -0.12065 -0.3048)
			(stroke
				(width 0.1)
				(type default)
			)
			(layer "B.Fab")
		)
		(fp_line
			(start 0.12065 0.2794)
			(end 0.12065 0.3048)
			(stroke
				(width 0.1)
				(type default)
			)
			(layer "B.Fab")
		)
		(fp_line
			(start -0.120396 0.2794)
			(end 0.12065 0.2794)
			(stroke
				(width 0.1)
				(type default)
			)
			(layer "B.Fab")
		)
		(fp_line
			(start 0.67945 0.3048)
			(end 0.67945 -0.305054)
			(stroke
				(width 0.1)
				(type default)
			)
			(layer "B.Fab")
		)
		(fp_line
			(start 0.12065 0.3048)
			(end 0.67945 0.3048)
			(stroke
				(width 0.1)
				(type default)
			)
			(layer "B.Fab")
		)
		(fp_line
			(start -0.120396 0.3048)
			(end -0.120396 0.2794)
			(stroke
				(width 0.1)
				(type default)
			)
			(layer "B.Fab")
		)
		(fp_line
			(start -0.67945 0.3048)
			(end -0.120396 0.3048)
			(stroke
				(width 0.1)
				(type default)
			)
			(layer "B.Fab")
		)
		(pad "1" smd circle
			(at 0.40005 0 270)
			(size 0 0)
			(layers "B.Cu" "B.Mask" "B.Paste")
			(net "DBP_CPU0_MBP0_GTL_R_N")
		)
		(pad "2" smd circle
			(at -0.40005 0 270)
			(size 0 0)
			(layers "B.Cu" "B.Mask" "B.Paste")
			(net "DBP_CPU_MBP0_GTL_N")
		)
	)
)
